(kicad_pcb
	(version 20260206)
	(generator "pcbnew")
	(generator_version "10.0")
	(general
		(thickness 1.6)
		(legacy_teardrops no)
	)
	(paper "A4")
	(title_block
		(title "Wiwynn_Tioga_Pass_MB.brd")
		(comment 1 "Tioga Pass / footprints 2366-2373 of 4770")
	)
	(layers
		(0 "F.Cu" signal "TOP")
		(4 "In1.Cu" signal "L2GND")
		(6 "In2.Cu" signal "L3")
		(8 "In3.Cu" signal "L4GND")
		(10 "In4.Cu" signal "L5")
		(12 "In5.Cu" signal "L6GND")
		(14 "In6.Cu" signal "L7VCC")
		(16 "In7.Cu" signal "L8VCC")
		(18 "In8.Cu" signal "L9GND")
		(20 "In9.Cu" signal "L10")
		(22 "In10.Cu" signal "L11GND")
		(24 "In11.Cu" signal "L12")
		(26 "In12.Cu" signal "L13GND")
		(2 "B.Cu" signal "BOTTOM")
		(9 "F.Adhes" user "F.Adhesive")
		(11 "B.Adhes" user "B.Adhesive")
		(13 "F.Paste" user "Package Geometry/Pastemask Top")
		(15 "B.Paste" user "Package Geometry/Pastemask Bottom")
		(5 "F.SilkS" user "Ref Des/Silkscreen Top")
		(7 "B.SilkS" user "Ref Des/Silkscreen Bottom")
		(1 "F.Mask" user "Board Geometry/Soldermask Top")
		(3 "B.Mask" user "Board Geometry/Soldermask Bottom")
		(17 "Dwgs.User" user "User.Drawings")
		(19 "Cmts.User" user "User.Comments")
		(21 "Eco1.User" user "User.Eco1")
		(23 "Eco2.User" user "User.Eco2")
		(25 "Edge.Cuts" user "Board Geometry/Outline")
		(27 "Margin" user)
		(31 "F.CrtYd" user "Package Geometry/Place Bound Top")
		(29 "B.CrtYd" user "Package Geometry/Place Bound Bottom")
		(35 "F.Fab" user "Ref Des/Assembly Top")
		(33 "B.Fab" user "Ref Des/Assembly Bottom")
	)
	(footprint ""
		(layer "B.Cu")
		(at 258.1656 -3.321812 -90)
		(property "Reference" "C5G54"
			(at -1.14681 0.76708 0)
			(unlocked yes)
			(layer "B.SilkS")
			(effects
				(font
					(size 0.7874 0.5842)
					(thickness 0.1524)
				)
				(justify mirror)
			)
		)
		(property "Value" ""
			(at 0 0 90)
			(layer "B.Fab")
			(effects
				(font
					(size 1.27 1.27)
				)
				(justify mirror)
			)
		)
		(duplicate_pad_numbers_are_jumpers no)
		(fp_rect
			(start 0.4953 1.6002)
			(end -0.4953 -0.2032)
			(stroke
				(width 0)
				(type default)
			)
			(fill no)
			(layer "B.CrtYd")
		)
		(fp_line
			(start -0.4953 1.6002)
			(end 0.4953 1.6002)
			(stroke
				(width 0.1)
				(type default)
			)
			(layer "B.Fab")
		)
		(fp_line
			(start 0.4953 1.6002)
			(end 0.4953 -0.2032)
			(stroke
				(width 0.1)
				(type default)
			)
			(layer "B.Fab")
		)
		(fp_line
			(start -0.4953 -0.2032)
			(end -0.4953 1.6002)
			(stroke
				(width 0.1)
				(type default)
			)
			(layer "B.Fab")
		)
		(fp_line
			(start 0.4953 -0.2032)
			(end -0.4953 -0.2032)
			(stroke
				(width 0.1)
				(type default)
			)
			(layer "B.Fab")
		)
		(pad "1" smd rect
			(at 0 0 90)
			(size 0.762 0.889)
			(layers "B.Cu" "B.Mask" "B.Paste")
			(net "PVDDQ_ABC")
		)
		(pad "2" smd rect
			(at 0 1.397 90)
			(size 0.762 0.889)
			(layers "B.Cu" "B.Mask" "B.Paste")
			(net "GND")
		)
		(zone
			(layer "B.Cu")
			(hatch none 0.5)
			(connect_pads
				(clearance 0)
			)
			(min_thickness 0.25)
			(keepout
				(tracks not_allowed)
				(vias allowed)
				(pads allowed)
				(copperpour not_allowed)
				(footprints allowed)
			)
			(placement
				(enabled no)
				(sheetname "")
			)
			(fill
				(thermal_gap 0.5)
				(thermal_bridge_width 0.5)
				(island_removal_mode 0)
			)
			(polygon
				(pts
					(xy 257.2131 -2.940812) (xy 257.7211 -2.940812) (xy 257.7211 -3.702812) (xy 257.2131 -3.702812)
				)
			)
		)
	)
	(footprint ""
		(layer "B.Cu")
		(at 258.548886 -77.82814)
		(property "Reference" "C5P27"
			(at 0 0 0)
			(layer "B.SilkS")
			(hide yes)
			(effects
				(font
					(size 1.27 1.27)
				)
				(justify mirror)
			)
		)
		(property "Value" ""
			(at 0 0 0)
			(layer "B.Fab")
			(effects
				(font
					(size 1.27 1.27)
				)
				(justify mirror)
			)
		)
		(duplicate_pad_numbers_are_jumpers no)
		(fp_poly
			(pts
				(xy 0.7239 -0.2159) (xy -0.7239 -0.2159) (xy -0.7239 1.9939) (xy 0.7239 1.9939)
			)
			(stroke
				(width 0)
				(type default)
			)
			(fill no)
			(layer "B.CrtYd")
		)
		(fp_line
			(start -0.7239 -0.2159)
			(end 0.7239 -0.2159)
			(stroke
				(width 0.1)
				(type default)
			)
			(layer "B.Fab")
		)
		(fp_line
			(start -0.7239 1.9939)
			(end -0.7239 -0.2159)
			(stroke
				(width 0.1)
				(type default)
			)
			(layer "B.Fab")
		)
		(fp_line
			(start 0.7239 -0.2159)
			(end 0.7239 1.9939)
			(stroke
				(width 0.1)
				(type default)
			)
			(layer "B.Fab")
		)
		(fp_line
			(start 0.7239 1.9939)
			(end -0.7239 1.9939)
			(stroke
				(width 0.1)
				(type default)
			)
			(layer "B.Fab")
		)
		(pad "1" smd rect
			(at 0 0 180)
			(size 1.27 1.016)
			(layers "B.Cu" "B.Mask" "B.Paste")
			(net "PVCCIN_CPU0")
		)
		(pad "2" smd rect
			(at 0 1.778 180)
			(size 1.27 1.016)
			(layers "B.Cu" "B.Mask" "B.Paste")
			(net "GND")
		)
		(zone
			(layer "B.Cu")
			(hatch none 0.5)
			(connect_pads
				(clearance 0)
			)
			(min_thickness 0.25)
			(keepout
				(tracks not_allowed)
				(vias allowed)
				(pads allowed)
				(copperpour not_allowed)
				(footprints allowed)
			)
			(placement
				(enabled no)
				(sheetname "")
			)
			(fill
				(thermal_gap 0.5)
				(thermal_bridge_width 0.5)
				(island_removal_mode 0)
			)
			(polygon
				(pts
					(xy 259.183886 -77.32014) (xy 257.913886 -77.32014) (xy 257.913886 -76.55814) (xy 259.183886 -76.55814)
				)
			)
		)
	)
	(footprint ""
		(layer "B.Cu")
		(at 110.318296 -156.910024 -90)
		(property "Reference" "C7L1"
			(at 0 0 90)
			(layer "B.SilkS")
			(hide yes)
			(effects
				(font
					(size 1.27 1.27)
				)
				(justify mirror)
			)
		)
		(property "Value" ""
			(at 0 0 90)
			(layer "B.Fab")
			(effects
				(font
					(size 1.27 1.27)
				)
				(justify mirror)
			)
		)
		(duplicate_pad_numbers_are_jumpers no)
		(fp_poly
			(pts
				(xy 0.7239 -0.2159) (xy -0.7239 -0.2159) (xy -0.7239 1.9939) (xy 0.7239 1.9939)
			)
			(stroke
				(width 0)
				(type default)
			)
			(fill no)
			(layer "B.CrtYd")
		)
		(fp_line
			(start -0.7239 1.9939)
			(end -0.7239 -0.2159)
			(stroke
				(width 0.1)
				(type default)
			)
			(layer "B.Fab")
		)
		(fp_line
			(start 0.7239 1.9939)
			(end -0.7239 1.9939)
			(stroke
				(width 0.1)
				(type default)
			)
			(layer "B.Fab")
		)
		(fp_line
			(start -0.7239 -0.2159)
			(end 0.7239 -0.2159)
			(stroke
				(width 0.1)
				(type default)
			)
			(layer "B.Fab")
		)
		(fp_line
			(start 0.7239 -0.2159)
			(end 0.7239 1.9939)
			(stroke
				(width 0.1)
				(type default)
			)
			(layer "B.Fab")
		)
		(pad "1" smd rect
			(at 0 0 90)
			(size 1.27 1.016)
			(layers "B.Cu" "B.Mask" "B.Paste")
			(net "PVDDQ_KLM")
		)
		(pad "2" smd rect
			(at 0 1.778 90)
			(size 1.27 1.016)
			(layers "B.Cu" "B.Mask" "B.Paste")
			(net "GND")
		)
		(zone
			(layer "B.Cu")
			(hatch none 0.5)
			(connect_pads
				(clearance 0)
			)
			(min_thickness 0.25)
			(keepout
				(tracks not_allowed)
				(vias allowed)
				(pads allowed)
				(copperpour not_allowed)
				(footprints allowed)
			)
			(placement
				(enabled no)
				(sheetname "")
			)
			(fill
				(thermal_gap 0.5)
				(thermal_bridge_width 0.5)
				(island_removal_mode 0)
			)
			(polygon
				(pts
					(xy 109.810296 -156.275024) (xy 109.810296 -157.545024) (xy 109.048296 -157.545024) (xy 109.048296 -156.275024)
				)
			)
		)
	)
	(footprint ""
		(layer "B.Cu")
		(at 14.66723 -122.874278 180)
		(property "Reference" "C10W1"
			(at -1.47828 0.78994 270)
			(unlocked yes)
			(layer "B.SilkS")
			(effects
				(font
					(size 0.4064 0.254)
					(thickness 0.1524)
				)
				(justify mirror)
			)
		)
		(property "Value" ""
			(at 0 0 0)
			(layer "B.Fab")
			(effects
				(font
					(size 1.27 1.27)
				)
				(justify mirror)
			)
		)
		(duplicate_pad_numbers_are_jumpers no)
		(fp_poly
			(pts
				(xy 0.7239 -0.2159) (xy -0.7239 -0.2159) (xy -0.7239 1.9939) (xy 0.7239 1.9939)
			)
			(stroke
				(width 0)
				(type default)
			)
			(fill no)
			(layer "B.CrtYd")
		)
		(fp_line
			(start 0.7239 1.9939)
			(end -0.7239 1.9939)
			(stroke
				(width 0.1)
				(type default)
			)
			(layer "B.Fab")
		)
		(fp_line
			(start 0.7239 -0.2159)
			(end 0.7239 1.9939)
			(stroke
				(width 0.1)
				(type default)
			)
			(layer "B.Fab")
		)
		(fp_line
			(start -0.7239 1.9939)
			(end -0.7239 -0.2159)
			(stroke
				(width 0.1)
				(type default)
			)
			(layer "B.Fab")
		)
		(fp_line
			(start -0.7239 -0.2159)
			(end 0.7239 -0.2159)
			(stroke
				(width 0.1)
				(type default)
			)
			(layer "B.Fab")
		)
		(pad "1" smd rect
			(at 0 0)
			(size 1.27 1.016)
			(layers "B.Cu" "B.Mask" "B.Paste")
			(net "P12V_PUMP")
		)
		(pad "2" smd rect
			(at 0 1.778)
			(size 1.27 1.016)
			(layers "B.Cu" "B.Mask" "B.Paste")
			(net "GND")
		)
		(zone
			(layer "B.Cu")
			(hatch none 0.5)
			(connect_pads
				(clearance 0)
			)
			(min_thickness 0.25)
			(keepout
				(tracks not_allowed)
				(vias allowed)
				(pads allowed)
				(copperpour not_allowed)
				(footprints allowed)
			)
			(placement
				(enabled no)
				(sheetname "")
			)
			(fill
				(thermal_gap 0.5)
				(thermal_bridge_width 0.5)
				(island_removal_mode 0)
			)
			(polygon
				(pts
					(xy 14.03223 -123.382278) (xy 15.30223 -123.382278) (xy 15.30223 -124.144278) (xy 14.03223 -124.144278)
				)
			)
		)
	)
	(footprint ""
		(layer "B.Cu")
		(at 410.464 -149.95652 90)
		(property "Reference" "C2L18"
			(at 0 0 90)
			(layer "B.SilkS")
			(hide yes)
			(effects
				(font
					(size 1.27 1.27)
				)
				(justify mirror)
			)
		)
		(property "Value" ""
			(at 0 0 90)
			(layer "B.Fab")
			(effects
				(font
					(size 1.27 1.27)
				)
				(justify mirror)
			)
		)
		(duplicate_pad_numbers_are_jumpers no)
		(fp_poly
			(pts
				(xy -0.3048 -0.1016) (xy -0.3048 0.9906) (xy 0.3048 0.9906) (xy 0.3048 -0.1016)
			)
			(stroke
				(width 0)
				(type default)
			)
			(fill no)
			(layer "B.CrtYd")
		)
		(fp_line
			(start 0.3048 -0.1016)
			(end 0.3048 0.9906)
			(stroke
				(width 0.1)
				(type default)
			)
			(layer "B.Fab")
		)
		(fp_line
			(start -0.3048 -0.1016)
			(end 0.3048 -0.1016)
			(stroke
				(width 0.1)
				(type default)
			)
			(layer "B.Fab")
		)
		(fp_line
			(start 0.3048 0.9906)
			(end -0.3048 0.9906)
			(stroke
				(width 0.1)
				(type default)
			)
			(layer "B.Fab")
		)
		(fp_line
			(start -0.3048 0.9906)
			(end -0.3048 -0.1016)
			(stroke
				(width 0.1)
				(type default)
			)
			(layer "B.Fab")
		)
		(pad "1" smd rect
			(at 0 0 270)
			(size 0.508 0.508)
			(layers "B.Cu" "B.Mask" "B.Paste")
			(net "SATA6G_PCH_PCIE_UP_SATA_RXN<4>")
		)
		(pad "2" smd rect
			(at 0 0.889 270)
			(size 0.508 0.508)
			(layers "B.Cu" "B.Mask" "B.Paste")
			(net "SATA6G_P4_RX_C_DN")
		)
		(zone
			(layer "B.Cu")
			(hatch none 0.5)
			(connect_pads
				(clearance 0)
			)
			(min_thickness 0.25)
			(keepout
				(tracks allowed)
				(vias not_allowed)
				(pads allowed)
				(copperpour not_allowed)
				(footprints allowed)
			)
			(placement
				(enabled no)
				(sheetname "")
			)
			(fill
				(thermal_gap 0.5)
				(thermal_bridge_width 0.5)
				(island_removal_mode 0)
			)
			(polygon
				(pts
					(xy 410.718 -150.21052) (xy 410.718 -149.70252) (xy 411.099 -149.70252) (xy 411.099 -150.21052)
				)
			)
		)
		(zone
			(layer "B.Cu")
			(hatch none 0.5)
			(connect_pads
				(clearance 0)
			)
			(min_thickness 0.25)
			(keepout
				(tracks not_allowed)
				(vias allowed)
				(pads allowed)
				(copperpour not_allowed)
				(footprints allowed)
			)
			(placement
				(enabled no)
				(sheetname "")
			)
			(fill
				(thermal_gap 0.5)
				(thermal_bridge_width 0.5)
				(island_removal_mode 0)
			)
			(polygon
				(pts
					(xy 411.099 -150.21052) (xy 411.099 -149.70252) (xy 410.718 -149.70252) (xy 410.718 -150.21052)
				)
			)
		)
	)
	(footprint ""
		(layer "B.Cu")
		(at 110.388654 -79.60614 180)
		(property "Reference" "C7P6"
			(at 0 0 0)
			(layer "B.SilkS")
			(hide yes)
			(effects
				(font
					(size 1.27 1.27)
				)
				(justify mirror)
			)
		)
		(property "Value" ""
			(at 0 0 0)
			(layer "B.Fab")
			(effects
				(font
					(size 1.27 1.27)
				)
				(justify mirror)
			)
		)
		(duplicate_pad_numbers_are_jumpers no)
		(fp_poly
			(pts
				(xy 0.7239 -0.2159) (xy -0.7239 -0.2159) (xy -0.7239 1.9939) (xy 0.7239 1.9939)
			)
			(stroke
				(width 0)
				(type default)
			)
			(fill no)
			(layer "B.CrtYd")
		)
		(fp_line
			(start 0.7239 1.9939)
			(end -0.7239 1.9939)
			(stroke
				(width 0.1)
				(type default)
			)
			(layer "B.Fab")
		)
		(fp_line
			(start 0.7239 -0.2159)
			(end 0.7239 1.9939)
			(stroke
				(width 0.1)
				(type default)
			)
			(layer "B.Fab")
		)
		(fp_line
			(start -0.7239 1.9939)
			(end -0.7239 -0.2159)
			(stroke
				(width 0.1)
				(type default)
			)
			(layer "B.Fab")
		)
		(fp_line
			(start -0.7239 -0.2159)
			(end 0.7239 -0.2159)
			(stroke
				(width 0.1)
				(type default)
			)
			(layer "B.Fab")
		)
		(pad "1" smd rect
			(at 0 0)
			(size 1.27 1.016)
			(layers "B.Cu" "B.Mask" "B.Paste")
			(net "PVCCMCP_CPU1")
		)
		(pad "2" smd rect
			(at 0 1.778)
			(size 1.27 1.016)
			(layers "B.Cu" "B.Mask" "B.Paste")
			(net "GND")
		)
		(zone
			(layer "B.Cu")
			(hatch none 0.5)
			(connect_pads
				(clearance 0)
			)
			(min_thickness 0.25)
			(keepout
				(tracks not_allowed)
				(vias allowed)
				(pads allowed)
				(copperpour not_allowed)
				(footprints allowed)
			)
			(placement
				(enabled no)
				(sheetname "")
			)
			(fill
				(thermal_gap 0.5)
				(thermal_bridge_width 0.5)
				(island_removal_mode 0)
			)
			(polygon
				(pts
					(xy 109.753654 -80.11414) (xy 111.023654 -80.11414) (xy 111.023654 -80.87614) (xy 109.753654 -80.87614)
				)
			)
		)
	)
	(footprint ""
		(layer "B.Cu")
		(at 375.062242 -40.662352 -90)
		(property "Reference" "R2T20"
			(at 0 0 90)
			(layer "B.SilkS")
			(hide yes)
			(effects
				(font
					(size 1.27 1.27)
				)
				(justify mirror)
			)
		)
		(property "Value" ""
			(at 0 0 90)
			(layer "B.Fab")
			(effects
				(font
					(size 1.27 1.27)
				)
				(justify mirror)
			)
		)
		(duplicate_pad_numbers_are_jumpers no)
		(fp_poly
			(pts
				(xy 0.2794 -0.1016) (xy -0.2794 -0.1016) (xy -0.2794 0.9906) (xy 0.2794 0.9906)
			)
			(stroke
				(width 0)
				(type default)
			)
			(fill no)
			(layer "B.CrtYd")
		)
		(fp_line
			(start -0.2794 0.9906)
			(end -0.2794 -0.1016)
			(stroke
				(width 0.1)
				(type default)
			)
			(layer "B.Fab")
		)
		(fp_line
			(start 0.2794 0.9906)
			(end -0.2794 0.9906)
			(stroke
				(width 0.1)
				(type default)
			)
			(layer "B.Fab")
		)
		(fp_line
			(start -0.2794 -0.1016)
			(end 0.2794 -0.1016)
			(stroke
				(width 0.1)
				(type default)
			)
			(layer "B.Fab")
		)
		(fp_line
			(start 0.2794 -0.1016)
			(end 0.2794 0.9906)
			(stroke
				(width 0.1)
				(type default)
			)
			(layer "B.Fab")
		)
		(pad "1" smd rect
			(at 0 0 90)
			(size 0.508 0.508)
			(layers "B.Cu" "B.Mask" "B.Paste")
			(net "H_CPU1_ERR0_G_N")
		)
		(pad "2" smd rect
			(at 0 0.889 90)
			(size 0.508 0.508)
			(layers "B.Cu" "B.Mask" "B.Paste")
			(net "H_CPU_ERR0_GTL_R_N")
		)
		(zone
			(layer "B.Cu")
			(hatch none 0.5)
			(connect_pads
				(clearance 0)
			)
			(min_thickness 0.25)
			(keepout
				(tracks not_allowed)
				(vias allowed)
				(pads allowed)
				(copperpour not_allowed)
				(footprints allowed)
			)
			(placement
				(enabled no)
				(sheetname "")
			)
			(fill
				(thermal_gap 0.5)
				(thermal_bridge_width 0.5)
				(island_removal_mode 0)
			)
			(polygon
				(pts
					(xy 374.427242 -40.408352) (xy 374.427242 -40.916352) (xy 374.808242 -40.916352) (xy 374.808242 -40.408352)
				)
			)
		)
		(zone
			(layer "B.Cu")
			(hatch none 0.5)
			(connect_pads
				(clearance 0)
			)
			(min_thickness 0.25)
			(keepout
				(tracks allowed)
				(vias not_allowed)
				(pads allowed)
				(copperpour not_allowed)
				(footprints allowed)
			)
			(placement
				(enabled no)
				(sheetname "")
			)
			(fill
				(thermal_gap 0.5)
				(thermal_bridge_width 0.5)
				(island_removal_mode 0)
			)
			(polygon
				(pts
					(xy 374.808242 -40.408352) (xy 374.808242 -40.916352) (xy 374.427242 -40.916352) (xy 374.427242 -40.408352)
				)
			)
		)
	)
	(footprint ""
		(layer "B.Cu")
		(at 412.75 -46.052232)
		(property "Reference" "R25W74"
			(at 0.8382 -0.67818 0)
			(unlocked yes)
			(layer "B.SilkS")
			(effects
				(font
					(size 0.4064 0.254)
					(thickness 0.1524)
				)
				(justify left mirror)
			)
		)
		(property "Value" ""
			(at 0 0 0)
			(layer "B.Fab")
			(effects
				(font
					(size 1.27 1.27)
				)
				(justify mirror)
			)
		)
		(duplicate_pad_numbers_are_jumpers no)
		(fp_poly
			(pts
				(xy 0.2794 -0.1016) (xy -0.2794 -0.1016) (xy -0.2794 0.9906) (xy 0.2794 0.9906)
			)
			(stroke
				(width 0)
				(type default)
			)
			(fill no)
			(layer "B.CrtYd")
		)
		(fp_line
			(start -0.2794 -0.1016)
			(end 0.2794 -0.1016)
			(stroke
				(width 0.1)
				(type default)
			)
			(layer "B.Fab")
		)
		(fp_line
			(start -0.2794 0.9906)
			(end -0.2794 -0.1016)
			(stroke
				(width 0.1)
				(type default)
			)
			(layer "B.Fab")
		)
		(fp_line
			(start 0.2794 -0.1016)
			(end 0.2794 0.9906)
			(stroke
				(width 0.1)
				(type default)
			)
			(layer "B.Fab")
		)
		(fp_line
			(start 0.2794 0.9906)
			(end -0.2794 0.9906)
			(stroke
				(width 0.1)
				(type default)
			)
			(layer "B.Fab")
		)
		(pad "1" smd rect
			(at 0 0 180)
			(size 0.508 0.508)
			(layers "B.Cu" "B.Mask" "B.Paste")
			(net "RST_PLTRST_BUF_N")
		)
		(pad "2" smd rect
			(at 0 0.889 180)
			(size 0.508 0.508)
			(layers "B.Cu" "B.Mask" "B.Paste")
			(net "RST_BMC_LVC3_N")
		)
		(zone
			(layer "B.Cu")
			(hatch none 0.5)
			(connect_pads
				(clearance 0)
			)
			(min_thickness 0.25)
			(keepout
				(tracks allowed)
				(vias not_allowed)
				(pads allowed)
				(copperpour not_allowed)
				(footprints allowed)
			)
			(placement
				(enabled no)
				(sheetname "")
			)
			(fill
				(thermal_gap 0.5)
				(thermal_bridge_width 0.5)
				(island_removal_mode 0)
			)
			(polygon
				(pts
					(xy 413.004 -45.798232) (xy 412.496 -45.798232) (xy 412.496 -45.417232) (xy 413.004 -45.417232)
				)
			)
		)
		(zone
			(layer "B.Cu")
			(hatch none 0.5)
			(connect_pads
				(clearance 0)
			)
			(min_thickness 0.25)
			(keepout
				(tracks not_allowed)
				(vias allowed)
				(pads allowed)
				(copperpour not_allowed)
				(footprints allowed)
			)
			(placement
				(enabled no)
				(sheetname "")
			)
			(fill
				(thermal_gap 0.5)
				(thermal_bridge_width 0.5)
				(island_removal_mode 0)
			)
			(polygon
				(pts
					(xy 413.004 -45.417232) (xy 412.496 -45.417232) (xy 412.496 -45.798232) (xy 413.004 -45.798232)
				)
			)
		)
	)
)
